(kicad_pcb
	(version 20260206)
	(generator "pcbnew")
	(generator_version "10.0")
	(general
		(thickness 1.6)
		(legacy_teardrops no)
	)
	(paper "A4")
	(title_block
		(title "12092022_DA0F0TFB6D0_F0T_FAN_BOARD_MP5048_D_brd_v02_OCP.brd")
		(comment 1 "Grand Teton / footprints 704-709 of 924")
	)
	(layers
		(0 "F.Cu" signal "TOP")
		(4 "In1.Cu" signal "GND")
		(6 "In2.Cu" signal "IN1")
		(8 "In3.Cu" signal "IN2")
		(10 "In4.Cu" signal "GND1")
		(2 "B.Cu" signal "BOTTOM")
		(9 "F.Adhes" user "F.Adhesive")
		(11 "B.Adhes" user "B.Adhesive")
		(13 "F.Paste" user "Package Geometry/Pastemask Top")
		(15 "B.Paste" user "Package Geometry/Pastemask Bottom")
		(5 "F.SilkS" user "Ref Des/Silkscreen Top")
		(7 "B.SilkS" user "Ref Des/Silkscreen Bottom")
		(1 "F.Mask" user "Board Geometry/Soldermask Top")
		(3 "B.Mask" user "Board Geometry/Soldermask Bottom")
		(17 "Dwgs.User" user "User.Drawings")
		(19 "Cmts.User" user "User.Comments")
		(21 "Eco1.User" user "User.Eco1")
		(23 "Eco2.User" user "User.Eco2")
		(25 "Edge.Cuts" user "Board Geometry/Outline")
		(27 "Margin" user)
		(31 "F.CrtYd" user "Package Geometry/Place Bound Top")
		(29 "B.CrtYd" user "Package Geometry/Place Bound Bottom")
		(35 "F.Fab" user "Ref Des/Assembly Top")
		(33 "B.Fab" user "Ref Des/Assembly Bottom")
	)
	(footprint ""
		(layer "F.Cu")
		(at 2.794 -31.496)
		(property "Reference" "R5703"
			(at 0 0 0)
			(layer "F.SilkS")
			(hide yes)
			(effects
				(font
					(size 1.27 1.27)
				)
			)
		)
		(property "Value" ""
			(at 0 0 0)
			(layer "F.Fab")
			(effects
				(font
					(size 1.27 1.27)
				)
			)
		)
		(duplicate_pad_numbers_are_jumpers no)
		(fp_line
			(start -0.7874 -0.4064)
			(end 0.7874 -0.4064)
			(stroke
				(width 0.1524)
				(type default)
			)
			(layer "F.SilkS")
		)
		(fp_line
			(start -0.7874 0.4064)
			(end -0.7874 -0.4064)
			(stroke
				(width 0.1524)
				(type default)
			)
			(layer "F.SilkS")
		)
		(fp_line
			(start 0.7874 -0.4064)
			(end 0.7874 0.4064)
			(stroke
				(width 0.1524)
				(type default)
			)
			(layer "F.SilkS")
		)
		(fp_line
			(start 0.7874 0.4064)
			(end -0.7874 0.4064)
			(stroke
				(width 0.1524)
				(type default)
			)
			(layer "F.SilkS")
		)
		(fp_line
			(start -0.67945 -0.305054)
			(end -0.12065 -0.305054)
			(stroke
				(width 0.1)
				(type default)
			)
			(layer "F.Fab")
		)
		(fp_line
			(start -0.67945 0.3048)
			(end -0.67945 -0.305054)
			(stroke
				(width 0.1)
				(type default)
			)
			(layer "F.Fab")
		)
		(fp_line
			(start -0.12065 -0.305054)
			(end -0.12065 -0.2794)
			(stroke
				(width 0.1)
				(type default)
			)
			(layer "F.Fab")
		)
		(fp_line
			(start -0.12065 -0.2794)
			(end 0.12065 -0.2794)
			(stroke
				(width 0.1)
				(type default)
			)
			(layer "F.Fab")
		)
		(fp_line
			(start -0.12065 0.2794)
			(end -0.12065 0.3048)
			(stroke
				(width 0.1)
				(type default)
			)
			(layer "F.Fab")
		)
		(fp_line
			(start -0.12065 0.3048)
			(end -0.67945 0.3048)
			(stroke
				(width 0.1)
				(type default)
			)
			(layer "F.Fab")
		)
		(fp_line
			(start 0.120396 0.2794)
			(end -0.12065 0.2794)
			(stroke
				(width 0.1)
				(type default)
			)
			(layer "F.Fab")
		)
		(fp_line
			(start 0.120396 0.3048)
			(end 0.120396 0.2794)
			(stroke
				(width 0.1)
				(type default)
			)
			(layer "F.Fab")
		)
		(fp_line
			(start 0.12065 -0.3048)
			(end 0.67945 -0.3048)
			(stroke
				(width 0.1)
				(type default)
			)
			(layer "F.Fab")
		)
		(fp_line
			(start 0.12065 -0.2794)
			(end 0.12065 -0.3048)
			(stroke
				(width 0.1)
				(type default)
			)
			(layer "F.Fab")
		)
		(fp_line
			(start 0.67945 -0.3048)
			(end 0.67945 0.3048)
			(stroke
				(width 0.1)
				(type default)
			)
			(layer "F.Fab")
		)
		(fp_line
			(start 0.67945 0.3048)
			(end 0.120396 0.3048)
			(stroke
				(width 0.1)
				(type default)
			)
			(layer "F.Fab")
		)
		(pad "1" smd rect
			(at -0.40005 0 180)
			(size 0.4572 0.508)
			(layers "F.Cu" "F.Mask" "F.Paste")
			(net "P12V_LED_FAN4")
		)
		(pad "2" smd rect
			(at 0.40005 0 180)
			(size 0.4572 0.508)
			(layers "F.Cu" "F.Mask" "F.Paste")
			(net "P12V_LED_R_FAN4")
		)
	)
	(footprint ""
		(layer "F.Cu")
		(at 6.477 -163.957)
		(property "Reference" "R99"
			(at 0 0 0)
			(layer "F.SilkS")
			(hide yes)
			(effects
				(font
					(size 1.27 1.27)
				)
			)
		)
		(property "Value" ""
			(at 0 0 0)
			(layer "F.Fab")
			(effects
				(font
					(size 1.27 1.27)
				)
			)
		)
		(duplicate_pad_numbers_are_jumpers no)
		(fp_line
			(start -0.7874 -0.4064)
			(end 0.7874 -0.4064)
			(stroke
				(width 0.1524)
				(type default)
			)
			(layer "F.SilkS")
		)
		(fp_line
			(start -0.7874 0.4064)
			(end -0.7874 -0.4064)
			(stroke
				(width 0.1524)
				(type default)
			)
			(layer "F.SilkS")
		)
		(fp_line
			(start 0.7874 -0.4064)
			(end 0.7874 0.4064)
			(stroke
				(width 0.1524)
				(type default)
			)
			(layer "F.SilkS")
		)
		(fp_line
			(start 0.7874 0.4064)
			(end -0.7874 0.4064)
			(stroke
				(width 0.1524)
				(type default)
			)
			(layer "F.SilkS")
		)
		(fp_line
			(start -0.67945 -0.305054)
			(end -0.12065 -0.305054)
			(stroke
				(width 0.1)
				(type default)
			)
			(layer "F.Fab")
		)
		(fp_line
			(start -0.67945 0.3048)
			(end -0.67945 -0.305054)
			(stroke
				(width 0.1)
				(type default)
			)
			(layer "F.Fab")
		)
		(fp_line
			(start -0.12065 -0.305054)
			(end -0.12065 -0.2794)
			(stroke
				(width 0.1)
				(type default)
			)
			(layer "F.Fab")
		)
		(fp_line
			(start -0.12065 -0.2794)
			(end 0.12065 -0.2794)
			(stroke
				(width 0.1)
				(type default)
			)
			(layer "F.Fab")
		)
		(fp_line
			(start -0.12065 0.2794)
			(end -0.12065 0.3048)
			(stroke
				(width 0.1)
				(type default)
			)
			(layer "F.Fab")
		)
		(fp_line
			(start -0.12065 0.3048)
			(end -0.67945 0.3048)
			(stroke
				(width 0.1)
				(type default)
			)
			(layer "F.Fab")
		)
		(fp_line
			(start 0.120396 0.2794)
			(end -0.12065 0.2794)
			(stroke
				(width 0.1)
				(type default)
			)
			(layer "F.Fab")
		)
		(fp_line
			(start 0.120396 0.3048)
			(end 0.120396 0.2794)
			(stroke
				(width 0.1)
				(type default)
			)
			(layer "F.Fab")
		)
		(fp_line
			(start 0.12065 -0.3048)
			(end 0.67945 -0.3048)
			(stroke
				(width 0.1)
				(type default)
			)
			(layer "F.Fab")
		)
		(fp_line
			(start 0.12065 -0.2794)
			(end 0.12065 -0.3048)
			(stroke
				(width 0.1)
				(type default)
			)
			(layer "F.Fab")
		)
		(fp_line
			(start 0.67945 -0.3048)
			(end 0.67945 0.3048)
			(stroke
				(width 0.1)
				(type default)
			)
			(layer "F.Fab")
		)
		(fp_line
			(start 0.67945 0.3048)
			(end 0.120396 0.3048)
			(stroke
				(width 0.1)
				(type default)
			)
			(layer "F.Fab")
		)
		(pad "1" smd circle
			(at -0.40005 0)
			(size 0 0)
			(layers "F.Cu" "F.Mask" "F.Paste")
			(net "P3V3_AUX")
		)
		(pad "2" smd circle
			(at 0.40005 0)
			(size 0 0)
			(layers "F.Cu" "F.Mask" "F.Paste")
			(net "FAN_1_PRSNT_BUF_R_N")
		)
	)
	(footprint ""
		(layer "F.Cu")
		(at 17.272 -294.64 180)
		(property "Reference" "U367"
			(at -2.667 1.11633 0)
			(unlocked yes)
			(layer "F.SilkS")
			(effects
				(font
					(size 0.7874 0.5842)
					(thickness 0.1524)
				)
				(justify left)
			)
		)
		(property "Value" ""
			(at 0 0 180)
			(layer "F.Fab")
			(effects
				(font
					(size 1.27 1.27)
				)
			)
		)
		(duplicate_pad_numbers_are_jumpers no)
		(fp_line
			(start 1.335278 1.100074)
			(end 1.335278 -1.100074)
			(stroke
				(width 0.1524)
				(type default)
			)
			(layer "F.SilkS")
		)
		(fp_line
			(start 1.335278 -1.100074)
			(end -1.335278 -1.100074)
			(stroke
				(width 0.1524)
				(type default)
			)
			(layer "F.SilkS")
		)
		(fp_line
			(start -1.335278 1.100074)
			(end 1.335278 1.100074)
			(stroke
				(width 0.1524)
				(type default)
			)
			(layer "F.SilkS")
		)
		(fp_line
			(start -1.335278 -1.100074)
			(end -1.335278 1.100074)
			(stroke
				(width 0.1524)
				(type default)
			)
			(layer "F.SilkS")
		)
		(fp_line
			(start 0.674878 1.100074)
			(end 0.674878 -1.100074)
			(stroke
				(width 0.1)
				(type default)
			)
			(layer "F.Fab")
		)
		(fp_line
			(start 0.674878 -1.100074)
			(end -0.674878 -1.100074)
			(stroke
				(width 0.1)
				(type default)
			)
			(layer "F.Fab")
		)
		(fp_line
			(start -0.674878 1.100074)
			(end 0.674878 1.100074)
			(stroke
				(width 0.1)
				(type default)
			)
			(layer "F.Fab")
		)
		(fp_line
			(start -0.674878 -1.100074)
			(end -0.674878 1.100074)
			(stroke
				(width 0.1)
				(type default)
			)
			(layer "F.Fab")
		)
		(pad "D" smd rect
			(at 0.8001 0 90)
			(size 0.6096 0.8128)
			(layers "F.Cu" "F.Mask" "F.Paste")
			(net "FAN_7_FAIL_LED_R_N")
		)
		(pad "G" smd rect
			(at -0.8001 -0.649986 90)
			(size 0.6096 0.8128)
			(layers "F.Cu" "F.Mask" "F.Paste")
			(net "FAN_7_FAIL_R_LED")
		)
		(pad "S" smd rect
			(at -0.8001 0.649986 90)
			(size 0.6096 0.8128)
			(layers "F.Cu" "F.Mask" "F.Paste")
			(net "GND")
		)
	)
	(footprint ""
		(layer "F.Cu")
		(at 15.504922 -30.566868 180)
		(property "Reference" "D114"
			(at 6.056122 0.000762 0)
			(unlocked yes)
			(layer "F.SilkS")
			(effects
				(font
					(size 0.7874 0.5842)
					(thickness 0.1524)
				)
				(justify left)
			)
		)
		(property "Value" ""
			(at 0 0 180)
			(layer "F.Fab")
			(effects
				(font
					(size 1.27 1.27)
				)
			)
		)
		(duplicate_pad_numbers_are_jumpers no)
		(fp_line
			(start 1.905 -0.6858)
			(end 1.905 0.6858)
			(stroke
				(width 0.1524)
				(type default)
			)
			(layer "F.SilkS")
		)
		(fp_line
			(start 1.865122 0.7112)
			(end -1.651 0.7112)
			(stroke
				(width 0.1524)
				(type default)
			)
			(layer "F.SilkS")
		)
		(fp_line
			(start 1.778 0.6858)
			(end 1.778 -0.6858)
			(stroke
				(width 0.1524)
				(type default)
			)
			(layer "F.SilkS")
		)
		(fp_line
			(start 1.651 -0.6858)
			(end 1.651 0.6858)
			(stroke
				(width 0.1524)
				(type default)
			)
			(layer "F.SilkS")
		)
		(fp_line
			(start 0.299974 -0.500126)
			(end 0.299974 0.500126)
			(stroke
				(width 0.1524)
				(type default)
			)
			(layer "F.SilkS")
		)
		(fp_line
			(start 0.199898 0)
			(end -0.299974 -0.500126)
			(stroke
				(width 0.1524)
				(type default)
			)
			(layer "F.SilkS")
		)
		(fp_line
			(start -0.299974 0.500126)
			(end 0.199898 0)
			(stroke
				(width 0.1524)
				(type default)
			)
			(layer "F.SilkS")
		)
		(fp_line
			(start -0.299974 -0.500126)
			(end -0.299974 0.500126)
			(stroke
				(width 0.1524)
				(type default)
			)
			(layer "F.SilkS")
		)
		(fp_line
			(start -1.651 0.7112)
			(end -1.651 -0.7112)
			(stroke
				(width 0.1524)
				(type default)
			)
			(layer "F.SilkS")
		)
		(fp_line
			(start -1.651 -0.7112)
			(end 1.814322 -0.7112)
			(stroke
				(width 0.1524)
				(type default)
			)
			(layer "F.SilkS")
		)
		(fp_line
			(start 1.35001 0.175006)
			(end 0.899922 0.175006)
			(stroke
				(width 0.1)
				(type default)
			)
			(layer "F.Fab")
		)
		(fp_line
			(start 1.35001 -0.225044)
			(end 1.35001 0.175006)
			(stroke
				(width 0.1)
				(type default)
			)
			(layer "F.Fab")
		)
		(fp_line
			(start 0.899922 0.700024)
			(end -0.899922 0.700024)
			(stroke
				(width 0.1)
				(type default)
			)
			(layer "F.Fab")
		)
		(fp_line
			(start 0.899922 0.175006)
			(end 0.899922 0.700024)
			(stroke
				(width 0.1)
				(type default)
			)
			(layer "F.Fab")
		)
		(fp_line
			(start 0.899922 -0.225044)
			(end 1.35001 -0.225044)
			(stroke
				(width 0.1)
				(type default)
			)
			(layer "F.Fab")
		)
		(fp_line
			(start 0.899922 -0.700024)
			(end 0.899922 -0.225044)
			(stroke
				(width 0.1)
				(type default)
			)
			(layer "F.Fab")
		)
		(fp_line
			(start 0.299974 -0.500126)
			(end 0.299974 0.500126)
			(stroke
				(width 0.1)
				(type default)
			)
			(layer "F.Fab")
		)
		(fp_line
			(start 0.199898 0)
			(end -0.299974 -0.500126)
			(stroke
				(width 0.1)
				(type default)
			)
			(layer "F.Fab")
		)
		(fp_line
			(start -0.299974 0.500126)
			(end 0.199898 0)
			(stroke
				(width 0.1)
				(type default)
			)
			(layer "F.Fab")
		)
		(fp_line
			(start -0.299974 -0.500126)
			(end -0.299974 0.500126)
			(stroke
				(width 0.1)
				(type default)
			)
			(layer "F.Fab")
		)
		(fp_line
			(start -0.899922 0.700024)
			(end -0.899922 0.175006)
			(stroke
				(width 0.1)
				(type default)
			)
			(layer "F.Fab")
		)
		(fp_line
			(start -0.899922 0.175006)
			(end -1.35001 0.175006)
			(stroke
				(width 0.1)
				(type default)
			)
			(layer "F.Fab")
		)
		(fp_line
			(start -0.899922 -0.225044)
			(end -0.899922 -0.700024)
			(stroke
				(width 0.1)
				(type default)
			)
			(layer "F.Fab")
		)
		(fp_line
			(start -0.899922 -0.700024)
			(end 0.899922 -0.700024)
			(stroke
				(width 0.1)
				(type default)
			)
			(layer "F.Fab")
		)
		(fp_line
			(start -1.35001 0.175006)
			(end -1.35001 -0.225044)
			(stroke
				(width 0.1)
				(type default)
			)
			(layer "F.Fab")
		)
		(fp_line
			(start -1.35001 -0.225044)
			(end -0.899922 -0.225044)
			(stroke
				(width 0.1)
				(type default)
			)
			(layer "F.Fab")
		)
		(fp_text user "-"
			(at 1.026922 0.833882 180)
			(unlocked yes)
			(layer "F.SilkS")
			(effects
				(font
					(size 1.905 1.4224)
					(thickness 0.1524)
				)
				(justify left)
			)
		)
		(fp_text user "+"
			(at -2.529078 1.087882 180)
			(unlocked yes)
			(layer "F.SilkS")
			(effects
				(font
					(size 1.905 1.4224)
					(thickness 0.1524)
				)
				(justify left)
			)
		)
		(fp_text user "-"
			(at 1.8288 -0.24765 180)
			(unlocked yes)
			(layer "F.Fab")
			(effects
				(font
					(size 1.905 1.4224)
					(thickness 0.1524)
				)
				(justify left)
			)
		)
		(fp_text user "+"
			(at -2.794 -0.19685 180)
			(unlocked yes)
			(layer "F.Fab")
			(effects
				(font
					(size 1.905 1.4224)
					(thickness 0.1524)
				)
				(justify left)
			)
		)
		(pad "1" smd rect
			(at -1.0922 0)
			(size 0.8128 0.8636)
			(layers "F.Cu" "F.Mask" "F.Paste")
			(net "FAN_4_TACH_OL_R")
		)
		(pad "2" smd rect
			(at 1.0922 0 180)
			(size 0.8128 0.8636)
			(layers "F.Cu" "F.Mask" "F.Paste")
			(net "FAN_4_TACH_OL_D")
		)
	)
	(footprint ""
		(layer "F.Cu")
		(at 25.781 -289.433)
		(property "Reference" "U329"
			(at -1.6129 -1.75387 0)
			(unlocked yes)
			(layer "F.SilkS")
			(effects
				(font
					(size 0.7874 0.5842)
					(thickness 0.1524)
				)
				(justify left)
			)
		)
		(property "Value" ""
			(at 0 0 0)
			(layer "F.Fab")
			(effects
				(font
					(size 1.27 1.27)
				)
			)
		)
		(duplicate_pad_numbers_are_jumpers no)
		(fp_line
			(start -1.538478 -1.150874)
			(end -1.538478 1.150874)
			(stroke
				(width 0.1524)
				(type default)
			)
			(layer "F.SilkS")
		)
		(fp_line
			(start -1.538478 1.150874)
			(end 1.538478 1.150874)
			(stroke
				(width 0.1524)
				(type default)
			)
			(layer "F.SilkS")
		)
		(fp_line
			(start 1.538478 -1.150874)
			(end -1.538478 -1.150874)
			(stroke
				(width 0.1524)
				(type default)
			)
			(layer "F.SilkS")
		)
		(fp_line
			(start 1.538478 1.150874)
			(end 1.538478 -1.150874)
			(stroke
				(width 0.1524)
				(type default)
			)
			(layer "F.SilkS")
		)
		(fp_line
			(start -0.674878 -1.100074)
			(end -0.674878 1.100074)
			(stroke
				(width 0.1)
				(type default)
			)
			(layer "F.Fab")
		)
		(fp_line
			(start -0.674878 1.100074)
			(end 0.674878 1.100074)
			(stroke
				(width 0.1)
				(type default)
			)
			(layer "F.Fab")
		)
		(fp_line
			(start 0.674878 -1.100074)
			(end -0.674878 -1.100074)
			(stroke
				(width 0.1)
				(type default)
			)
			(layer "F.Fab")
		)
		(fp_line
			(start 0.674878 1.100074)
			(end 0.674878 -1.100074)
			(stroke
				(width 0.1)
				(type default)
			)
			(layer "F.Fab")
		)
		(pad "1" smd rect
			(at -0.94996 -0.649986 90)
			(size 0.7112 0.9144)
			(layers "F.Cu" "F.Mask" "F.Paste")
			(net "FAN_7_PWM_IL")
		)
		(pad "2" smd rect
			(at -0.94996 0.649986 90)
			(size 0.7112 0.9144)
			(layers "F.Cu" "F.Mask" "F.Paste")
			(net "FAN_7_PWM_OL")
		)
		(pad "3" smd rect
			(at 0.94996 0 90)
			(size 0.7112 0.9144)
			(layers "F.Cu" "F.Mask" "F.Paste")
			(net "FAN_7_PWM_BUF")
		)
	)
	(footprint ""
		(layer "F.Cu")
		(at 27.813 -102.108 90)
		(property "Reference" "R5516"
			(at 0 0 90)
			(layer "F.SilkS")
			(hide yes)
			(effects
				(font
					(size 1.27 1.27)
				)
			)
		)
		(property "Value" ""
			(at 0 0 90)
			(layer "F.Fab")
			(effects
				(font
					(size 1.27 1.27)
				)
			)
		)
		(duplicate_pad_numbers_are_jumpers no)
		(fp_line
			(start 0.7874 -0.4064)
			(end 0.7874 0.4064)
			(stroke
				(width 0.1524)
				(type default)
			)
			(layer "F.SilkS")
		)
		(fp_line
			(start -0.7874 -0.4064)
			(end 0.7874 -0.4064)
			(stroke
				(width 0.1524)
				(type default)
			)
			(layer "F.SilkS")
		)
		(fp_line
			(start 0.7874 0.4064)
			(end -0.7874 0.4064)
			(stroke
				(width 0.1524)
				(type default)
			)
			(layer "F.SilkS")
		)
		(fp_line
			(start -0.7874 0.4064)
			(end -0.7874 -0.4064)
			(stroke
				(width 0.1524)
				(type default)
			)
			(layer "F.SilkS")
		)
		(fp_line
			(start -0.12065 -0.305054)
			(end -0.12065 -0.2794)
			(stroke
				(width 0.1)
				(type default)
			)
			(layer "F.Fab")
		)
		(fp_line
			(start -0.67945 -0.305054)
			(end -0.12065 -0.305054)
			(stroke
				(width 0.1)
				(type default)
			)
			(layer "F.Fab")
		)
		(fp_line
			(start 0.67945 -0.3048)
			(end 0.67945 0.3048)
			(stroke
				(width 0.1)
				(type default)
			)
			(layer "F.Fab")
		)
		(fp_line
			(start 0.12065 -0.3048)
			(end 0.67945 -0.3048)
			(stroke
				(width 0.1)
				(type default)
			)
			(layer "F.Fab")
		)
		(fp_line
			(start 0.12065 -0.2794)
			(end 0.12065 -0.3048)
			(stroke
				(width 0.1)
				(type default)
			)
			(layer "F.Fab")
		)
		(fp_line
			(start -0.12065 -0.2794)
			(end 0.12065 -0.2794)
			(stroke
				(width 0.1)
				(type default)
			)
			(layer "F.Fab")
		)
		(fp_line
			(start 0.120396 0.2794)
			(end -0.12065 0.2794)
			(stroke
				(width 0.1)
				(type default)
			)
			(layer "F.Fab")
		)
		(fp_line
			(start -0.12065 0.2794)
			(end -0.12065 0.3048)
			(stroke
				(width 0.1)
				(type default)
			)
			(layer "F.Fab")
		)
		(fp_line
			(start 0.67945 0.3048)
			(end 0.120396 0.3048)
			(stroke
				(width 0.1)
				(type default)
			)
			(layer "F.Fab")
		)
		(fp_line
			(start 0.120396 0.3048)
			(end 0.120396 0.2794)
			(stroke
				(width 0.1)
				(type default)
			)
			(layer "F.Fab")
		)
		(fp_line
			(start -0.12065 0.3048)
			(end -0.67945 0.3048)
			(stroke
				(width 0.1)
				(type default)
			)
			(layer "F.Fab")
		)
		(fp_line
			(start -0.67945 0.3048)
			(end -0.67945 -0.305054)
			(stroke
				(width 0.1)
				(type default)
			)
			(layer "F.Fab")
		)
		(pad "1" smd circle
			(at -0.40005 0 90)
			(size 0 0)
			(layers "F.Cu" "F.Mask" "F.Paste")
			(net "P3V3_AUX")
		)
		(pad "2" smd circle
			(at 0.40005 0 90)
			(size 0 0)
			(layers "F.Cu" "F.Mask" "F.Paste")
			(net "FAN_5_PWM_BUF")
		)
	)
)
